(kicad_pcb
	(version 20260206)
	(generator "pcbnew")
	(generator_version "10.0")
	(general
		(thickness 1.6)
		(legacy_teardrops no)
	)
	(paper "A4")
	(title_block
		(title "04192023_DAF0TMB3IC0_F0TG_MB_C_brd_V02_OCP.brd")
		(comment 1 "Grand Teton / footprints 5651-5657 of 8354")
	)
	(layers
		(0 "F.Cu" signal "TOP")
		(4 "In1.Cu" signal "GND")
		(6 "In2.Cu" signal "IN1")
		(8 "In3.Cu" signal "GND1")
		(10 "In4.Cu" signal "IN2")
		(12 "In5.Cu" signal "GND2")
		(14 "In6.Cu" signal "IN3")
		(16 "In7.Cu" signal "GND3")
		(18 "In8.Cu" signal "VCC")
		(20 "In9.Cu" signal "VCC1")
		(22 "In10.Cu" signal "GND4")
		(24 "In11.Cu" signal "IN4")
		(26 "In12.Cu" signal "GND5")
		(28 "In13.Cu" signal "IN5")
		(30 "In14.Cu" signal "GND6")
		(32 "In15.Cu" signal "IN6")
		(34 "In16.Cu" signal "GND7")
		(2 "B.Cu" signal "BOTTOM")
		(9 "F.Adhes" user "F.Adhesive")
		(11 "B.Adhes" user "B.Adhesive")
		(13 "F.Paste" user "Package Geometry/Pastemask Top")
		(15 "B.Paste" user "Package Geometry/Pastemask Bottom")
		(5 "F.SilkS" user "Ref Des/Silkscreen Top")
		(7 "B.SilkS" user "Ref Des/Silkscreen Bottom")
		(1 "F.Mask" user "Board Geometry/Soldermask Top")
		(3 "B.Mask" user "Board Geometry/Soldermask Bottom")
		(17 "Dwgs.User" user "User.Drawings")
		(19 "Cmts.User" user "User.Comments")
		(21 "Eco1.User" user "User.Eco1")
		(23 "Eco2.User" user "User.Eco2")
		(25 "Edge.Cuts" user "Board Geometry/Outline")
		(27 "Margin" user)
		(31 "F.CrtYd" user "Package Geometry/Place Bound Top")
		(29 "B.CrtYd" user "Package Geometry/Place Bound Bottom")
		(35 "F.Fab" user "Ref Des/Assembly Top")
		(33 "B.Fab" user "Ref Des/Assembly Bottom")
	)
	(footprint ""
		(layer "B.Cu")
		(at 255.905 -334.01 180)
		(property "Reference" "R833"
			(at 0 0 0)
			(layer "B.SilkS")
			(hide yes)
			(effects
				(font
					(size 1.27 1.27)
				)
				(justify mirror)
			)
		)
		(property "Value" ""
			(at 0 0 0)
			(layer "B.Fab")
			(effects
				(font
					(size 1.27 1.27)
				)
				(justify mirror)
			)
		)
		(duplicate_pad_numbers_are_jumpers no)
		(fp_line
			(start 0.32512 0.175006)
			(end 0.32512 -0.175006)
			(stroke
				(width 0.1)
				(type default)
			)
			(layer "B.Fab")
		)
		(fp_line
			(start 0.32512 -0.175006)
			(end -0.32512 -0.175006)
			(stroke
				(width 0.1)
				(type default)
			)
			(layer "B.Fab")
		)
		(fp_line
			(start -0.32512 0.175006)
			(end 0.32512 0.175006)
			(stroke
				(width 0.1)
				(type default)
			)
			(layer "B.Fab")
		)
		(fp_line
			(start -0.32512 -0.175006)
			(end -0.32512 0.175006)
			(stroke
				(width 0.1)
				(type default)
			)
			(layer "B.Fab")
		)
		(pad "1" smd rect
			(at 0.2667 0)
			(size 0.3048 0.381)
			(layers "B.Cu" "B.Mask" "B.Paste")
			(net "SMB_RT_CPU0_P2_ROM_MUX_2D_R_SCL")
		)
		(pad "2" smd rect
			(at -0.2667 0 180)
			(size 0.3048 0.381)
			(layers "B.Cu" "B.Mask" "B.Paste")
			(net "SMB_RT_CPU0_P2_ROM_MUX_2D_SCL")
		)
	)
	(footprint ""
		(layer "B.Cu")
		(at 361.046014 -257.744976 180)
		(property "Reference" "C3888"
			(at 0 0 0)
			(layer "B.SilkS")
			(hide yes)
			(effects
				(font
					(size 1.27 1.27)
				)
				(justify mirror)
			)
		)
		(property "Value" ""
			(at 0 0 0)
			(layer "B.Fab")
			(effects
				(font
					(size 1.27 1.27)
				)
				(justify mirror)
			)
		)
		(duplicate_pad_numbers_are_jumpers no)
		(fp_line
			(start 0.7874 0.4064)
			(end 0.7874 -0.4064)
			(stroke
				(width 0.1524)
				(type default)
			)
			(layer "B.SilkS")
		)
		(fp_line
			(start 0.7874 -0.4064)
			(end -0.7874 -0.4064)
			(stroke
				(width 0.1524)
				(type default)
			)
			(layer "B.SilkS")
		)
		(fp_line
			(start -0.7874 0.4064)
			(end 0.7874 0.4064)
			(stroke
				(width 0.1524)
				(type default)
			)
			(layer "B.SilkS")
		)
		(fp_line
			(start -0.7874 -0.4064)
			(end -0.7874 0.4064)
			(stroke
				(width 0.1524)
				(type default)
			)
			(layer "B.SilkS")
		)
		(fp_line
			(start 0.67945 0.3048)
			(end 0.67945 -0.305054)
			(stroke
				(width 0.1)
				(type default)
			)
			(layer "B.Fab")
		)
		(fp_line
			(start 0.67945 -0.305054)
			(end 0.12065 -0.305054)
			(stroke
				(width 0.1)
				(type default)
			)
			(layer "B.Fab")
		)
		(fp_line
			(start 0.12065 0.3048)
			(end 0.67945 0.3048)
			(stroke
				(width 0.1)
				(type default)
			)
			(layer "B.Fab")
		)
		(fp_line
			(start 0.12065 0.2794)
			(end 0.12065 0.3048)
			(stroke
				(width 0.1)
				(type default)
			)
			(layer "B.Fab")
		)
		(fp_line
			(start 0.12065 -0.2794)
			(end -0.12065 -0.2794)
			(stroke
				(width 0.1)
				(type default)
			)
			(layer "B.Fab")
		)
		(fp_line
			(start 0.12065 -0.305054)
			(end 0.12065 -0.2794)
			(stroke
				(width 0.1)
				(type default)
			)
			(layer "B.Fab")
		)
		(fp_line
			(start -0.120396 0.3048)
			(end -0.120396 0.2794)
			(stroke
				(width 0.1)
				(type default)
			)
			(layer "B.Fab")
		)
		(fp_line
			(start -0.120396 0.2794)
			(end 0.12065 0.2794)
			(stroke
				(width 0.1)
				(type default)
			)
			(layer "B.Fab")
		)
		(fp_line
			(start -0.12065 -0.2794)
			(end -0.12065 -0.3048)
			(stroke
				(width 0.1)
				(type default)
			)
			(layer "B.Fab")
		)
		(fp_line
			(start -0.12065 -0.3048)
			(end -0.67945 -0.3048)
			(stroke
				(width 0.1)
				(type default)
			)
			(layer "B.Fab")
		)
		(fp_line
			(start -0.67945 0.3048)
			(end -0.120396 0.3048)
			(stroke
				(width 0.1)
				(type default)
			)
			(layer "B.Fab")
		)
		(fp_line
			(start -0.67945 -0.3048)
			(end -0.67945 0.3048)
			(stroke
				(width 0.1)
				(type default)
			)
			(layer "B.Fab")
		)
		(pad "1" smd circle
			(at 0.40005 0)
			(size 0 0)
			(layers "B.Cu" "B.Mask" "B.Paste")
			(net "PVDDCR_SOC_P0")
		)
		(pad "2" smd circle
			(at -0.40005 0)
			(size 0 0)
			(layers "B.Cu" "B.Mask" "B.Paste")
			(net "GND")
		)
	)
	(footprint ""
		(layer "B.Cu")
		(at 183.54802 -423.011092 90)
		(property "Reference" "R8108"
			(at 0 0 90)
			(layer "B.SilkS")
			(hide yes)
			(effects
				(font
					(size 1.27 1.27)
				)
				(justify mirror)
			)
		)
		(property "Value" ""
			(at 0 0 90)
			(layer "B.Fab")
			(effects
				(font
					(size 1.27 1.27)
				)
				(justify mirror)
			)
		)
		(duplicate_pad_numbers_are_jumpers no)
		(fp_line
			(start 0.7874 -0.4064)
			(end -0.7874 -0.4064)
			(stroke
				(width 0.1524)
				(type default)
			)
			(layer "B.SilkS")
		)
		(fp_line
			(start -0.7874 -0.4064)
			(end -0.7874 0.4064)
			(stroke
				(width 0.1524)
				(type default)
			)
			(layer "B.SilkS")
		)
		(fp_line
			(start 0.7874 0.4064)
			(end 0.7874 -0.4064)
			(stroke
				(width 0.1524)
				(type default)
			)
			(layer "B.SilkS")
		)
		(fp_line
			(start -0.7874 0.4064)
			(end 0.7874 0.4064)
			(stroke
				(width 0.1524)
				(type default)
			)
			(layer "B.SilkS")
		)
		(fp_line
			(start 0.67945 -0.305054)
			(end 0.12065 -0.305054)
			(stroke
				(width 0.1)
				(type default)
			)
			(layer "B.Fab")
		)
		(fp_line
			(start 0.12065 -0.305054)
			(end 0.12065 -0.2794)
			(stroke
				(width 0.1)
				(type default)
			)
			(layer "B.Fab")
		)
		(fp_line
			(start -0.12065 -0.3048)
			(end -0.67945 -0.3048)
			(stroke
				(width 0.1)
				(type default)
			)
			(layer "B.Fab")
		)
		(fp_line
			(start -0.67945 -0.3048)
			(end -0.67945 0.3048)
			(stroke
				(width 0.1)
				(type default)
			)
			(layer "B.Fab")
		)
		(fp_line
			(start 0.12065 -0.2794)
			(end -0.12065 -0.2794)
			(stroke
				(width 0.1)
				(type default)
			)
			(layer "B.Fab")
		)
		(fp_line
			(start -0.12065 -0.2794)
			(end -0.12065 -0.3048)
			(stroke
				(width 0.1)
				(type default)
			)
			(layer "B.Fab")
		)
		(fp_line
			(start 0.12065 0.2794)
			(end 0.12065 0.3048)
			(stroke
				(width 0.1)
				(type default)
			)
			(layer "B.Fab")
		)
		(fp_line
			(start -0.120396 0.2794)
			(end 0.12065 0.2794)
			(stroke
				(width 0.1)
				(type default)
			)
			(layer "B.Fab")
		)
		(fp_line
			(start 0.67945 0.3048)
			(end 0.67945 -0.305054)
			(stroke
				(width 0.1)
				(type default)
			)
			(layer "B.Fab")
		)
		(fp_line
			(start 0.12065 0.3048)
			(end 0.67945 0.3048)
			(stroke
				(width 0.1)
				(type default)
			)
			(layer "B.Fab")
		)
		(fp_line
			(start -0.120396 0.3048)
			(end -0.120396 0.2794)
			(stroke
				(width 0.1)
				(type default)
			)
			(layer "B.Fab")
		)
		(fp_line
			(start -0.67945 0.3048)
			(end -0.120396 0.3048)
			(stroke
				(width 0.1)
				(type default)
			)
			(layer "B.Fab")
		)
		(pad "1" smd circle
			(at 0.40005 0 270)
			(size 0 0)
			(layers "B.Cu" "B.Mask" "B.Paste")
			(net "HSC_CSOUT")
		)
		(pad "2" smd circle
			(at -0.40005 0 270)
			(size 0 0)
			(layers "B.Cu" "B.Mask" "B.Paste")
			(net "HSC_OC_VOL")
		)
	)
	(footprint ""
		(layer "B.Cu")
		(at 335.70037 -393.88288 -90)
		(property "Reference" "C622"
			(at 0 0 90)
			(layer "B.SilkS")
			(hide yes)
			(effects
				(font
					(size 1.27 1.27)
				)
				(justify mirror)
			)
		)
		(property "Value" ""
			(at 0 0 90)
			(layer "B.Fab")
			(effects
				(font
					(size 1.27 1.27)
				)
				(justify mirror)
			)
		)
		(duplicate_pad_numbers_are_jumpers no)
		(fp_line
			(start -0.299974 0.150114)
			(end 0.299974 0.150114)
			(stroke
				(width 0.1)
				(type default)
			)
			(layer "B.Fab")
		)
		(fp_line
			(start 0.299974 0.150114)
			(end 0.299974 -0.150114)
			(stroke
				(width 0.1)
				(type default)
			)
			(layer "B.Fab")
		)
		(fp_line
			(start -0.299974 -0.150114)
			(end -0.299974 0.150114)
			(stroke
				(width 0.1)
				(type default)
			)
			(layer "B.Fab")
		)
		(fp_line
			(start 0.299974 -0.150114)
			(end -0.299974 -0.150114)
			(stroke
				(width 0.1)
				(type default)
			)
			(layer "B.Fab")
		)
		(pad "1" smd rect
			(at 0.2667 0 90)
			(size 0.3048 0.381)
			(layers "B.Cu" "B.Mask" "B.Paste")
			(net "P0V9_CPU0_RT1_2A")
		)
		(pad "2" smd rect
			(at -0.2667 0 90)
			(size 0.3048 0.381)
			(layers "B.Cu" "B.Mask" "B.Paste")
			(net "GND")
		)
	)
	(footprint ""
		(layer "B.Cu")
		(at 121.685812 -257.930396)
		(property "Reference" "C3914"
			(at 0 0 0)
			(layer "B.SilkS")
			(hide yes)
			(effects
				(font
					(size 1.27 1.27)
				)
				(justify mirror)
			)
		)
		(property "Value" ""
			(at 0 0 0)
			(layer "B.Fab")
			(effects
				(font
					(size 1.27 1.27)
				)
				(justify mirror)
			)
		)
		(duplicate_pad_numbers_are_jumpers no)
		(fp_line
			(start -0.7874 -0.4064)
			(end -0.7874 0.4064)
			(stroke
				(width 0.1524)
				(type default)
			)
			(layer "B.SilkS")
		)
		(fp_line
			(start -0.7874 0.4064)
			(end 0.7874 0.4064)
			(stroke
				(width 0.1524)
				(type default)
			)
			(layer "B.SilkS")
		)
		(fp_line
			(start 0.7874 -0.4064)
			(end -0.7874 -0.4064)
			(stroke
				(width 0.1524)
				(type default)
			)
			(layer "B.SilkS")
		)
		(fp_line
			(start 0.7874 0.4064)
			(end 0.7874 -0.4064)
			(stroke
				(width 0.1524)
				(type default)
			)
			(layer "B.SilkS")
		)
		(fp_line
			(start -0.67945 -0.3048)
			(end -0.67945 0.3048)
			(stroke
				(width 0.1)
				(type default)
			)
			(layer "B.Fab")
		)
		(fp_line
			(start -0.67945 0.3048)
			(end -0.120396 0.3048)
			(stroke
				(width 0.1)
				(type default)
			)
			(layer "B.Fab")
		)
		(fp_line
			(start -0.12065 -0.3048)
			(end -0.67945 -0.3048)
			(stroke
				(width 0.1)
				(type default)
			)
			(layer "B.Fab")
		)
		(fp_line
			(start -0.12065 -0.2794)
			(end -0.12065 -0.3048)
			(stroke
				(width 0.1)
				(type default)
			)
			(layer "B.Fab")
		)
		(fp_line
			(start -0.120396 0.2794)
			(end 0.12065 0.2794)
			(stroke
				(width 0.1)
				(type default)
			)
			(layer "B.Fab")
		)
		(fp_line
			(start -0.120396 0.3048)
			(end -0.120396 0.2794)
			(stroke
				(width 0.1)
				(type default)
			)
			(layer "B.Fab")
		)
		(fp_line
			(start 0.12065 -0.305054)
			(end 0.12065 -0.2794)
			(stroke
				(width 0.1)
				(type default)
			)
			(layer "B.Fab")
		)
		(fp_line
			(start 0.12065 -0.2794)
			(end -0.12065 -0.2794)
			(stroke
				(width 0.1)
				(type default)
			)
			(layer "B.Fab")
		)
		(fp_line
			(start 0.12065 0.2794)
			(end 0.12065 0.3048)
			(stroke
				(width 0.1)
				(type default)
			)
			(layer "B.Fab")
		)
		(fp_line
			(start 0.12065 0.3048)
			(end 0.67945 0.3048)
			(stroke
				(width 0.1)
				(type default)
			)
			(layer "B.Fab")
		)
		(fp_line
			(start 0.67945 -0.305054)
			(end 0.12065 -0.305054)
			(stroke
				(width 0.1)
				(type default)
			)
			(layer "B.Fab")
		)
		(fp_line
			(start 0.67945 0.3048)
			(end 0.67945 -0.305054)
			(stroke
				(width 0.1)
				(type default)
			)
			(layer "B.Fab")
		)
		(pad "1" smd circle
			(at 0.40005 0 180)
			(size 0 0)
			(layers "B.Cu" "B.Mask" "B.Paste")
			(net "PVDDCR_SOC_P1")
		)
		(pad "2" smd circle
			(at -0.40005 0 180)
			(size 0 0)
			(layers "B.Cu" "B.Mask" "B.Paste")
			(net "GND")
		)
	)
	(footprint ""
		(layer "B.Cu")
		(at 401.485608 -174.505874 90)
		(property "Reference" "PR362"
			(at 0 0 90)
			(layer "B.SilkS")
			(hide yes)
			(effects
				(font
					(size 1.27 1.27)
				)
				(justify mirror)
			)
		)
		(property "Value" ""
			(at 0 0 90)
			(layer "B.Fab")
			(effects
				(font
					(size 1.27 1.27)
				)
				(justify mirror)
			)
		)
		(duplicate_pad_numbers_are_jumpers no)
		(fp_line
			(start 0.7874 -0.4064)
			(end -0.7874 -0.4064)
			(stroke
				(width 0.1524)
				(type default)
			)
			(layer "B.SilkS")
		)
		(fp_line
			(start -0.7874 -0.4064)
			(end -0.7874 0.4064)
			(stroke
				(width 0.1524)
				(type default)
			)
			(layer "B.SilkS")
		)
		(fp_line
			(start 0.7874 0.4064)
			(end 0.7874 -0.4064)
			(stroke
				(width 0.1524)
				(type default)
			)
			(layer "B.SilkS")
		)
		(fp_line
			(start -0.7874 0.4064)
			(end 0.7874 0.4064)
			(stroke
				(width 0.1524)
				(type default)
			)
			(layer "B.SilkS")
		)
		(fp_line
			(start 0.67945 -0.305054)
			(end 0.12065 -0.305054)
			(stroke
				(width 0.1)
				(type default)
			)
			(layer "B.Fab")
		)
		(fp_line
			(start 0.12065 -0.305054)
			(end 0.12065 -0.2794)
			(stroke
				(width 0.1)
				(type default)
			)
			(layer "B.Fab")
		)
		(fp_line
			(start -0.12065 -0.3048)
			(end -0.67945 -0.3048)
			(stroke
				(width 0.1)
				(type default)
			)
			(layer "B.Fab")
		)
		(fp_line
			(start -0.67945 -0.3048)
			(end -0.67945 0.3048)
			(stroke
				(width 0.1)
				(type default)
			)
			(layer "B.Fab")
		)
		(fp_line
			(start 0.12065 -0.2794)
			(end -0.12065 -0.2794)
			(stroke
				(width 0.1)
				(type default)
			)
			(layer "B.Fab")
		)
		(fp_line
			(start -0.12065 -0.2794)
			(end -0.12065 -0.3048)
			(stroke
				(width 0.1)
				(type default)
			)
			(layer "B.Fab")
		)
		(fp_line
			(start 0.12065 0.2794)
			(end 0.12065 0.3048)
			(stroke
				(width 0.1)
				(type default)
			)
			(layer "B.Fab")
		)
		(fp_line
			(start -0.120396 0.2794)
			(end 0.12065 0.2794)
			(stroke
				(width 0.1)
				(type default)
			)
			(layer "B.Fab")
		)
		(fp_line
			(start 0.67945 0.3048)
			(end 0.67945 -0.305054)
			(stroke
				(width 0.1)
				(type default)
			)
			(layer "B.Fab")
		)
		(fp_line
			(start 0.12065 0.3048)
			(end 0.67945 0.3048)
			(stroke
				(width 0.1)
				(type default)
			)
			(layer "B.Fab")
		)
		(fp_line
			(start -0.120396 0.3048)
			(end -0.120396 0.2794)
			(stroke
				(width 0.1)
				(type default)
			)
			(layer "B.Fab")
		)
		(fp_line
			(start -0.67945 0.3048)
			(end -0.120396 0.3048)
			(stroke
				(width 0.1)
				(type default)
			)
			(layer "B.Fab")
		)
		(pad "1" smd circle
			(at 0.40005 0 270)
			(size 0 0)
			(layers "B.Cu" "B.Mask" "B.Paste")
			(net "PVDDCR_SOC_P0_VOS1")
		)
		(pad "2" smd circle
			(at -0.40005 0 270)
			(size 0 0)
			(layers "B.Cu" "B.Mask" "B.Paste")
			(net "PVDDCR_SOC_P0")
		)
	)
	(footprint ""
		(layer "B.Cu")
		(at 20.743418 -409.04287 90)
		(property "Reference" "PR6812"
			(at 0 0 90)
			(layer "B.SilkS")
			(hide yes)
			(effects
				(font
					(size 1.27 1.27)
				)
				(justify mirror)
			)
		)
		(property "Value" ""
			(at 0 0 90)
			(layer "B.Fab")
			(effects
				(font
					(size 1.27 1.27)
				)
				(justify mirror)
			)
		)
		(duplicate_pad_numbers_are_jumpers no)
		(fp_line
			(start 0.7874 -0.4064)
			(end -0.7874 -0.4064)
			(stroke
				(width 0.1524)
				(type default)
			)
			(layer "B.SilkS")
		)
		(fp_line
			(start -0.7874 -0.4064)
			(end -0.7874 0.4064)
			(stroke
				(width 0.1524)
				(type default)
			)
			(layer "B.SilkS")
		)
		(fp_line
			(start 0.7874 0.4064)
			(end 0.7874 -0.4064)
			(stroke
				(width 0.1524)
				(type default)
			)
			(layer "B.SilkS")
		)
		(fp_line
			(start -0.7874 0.4064)
			(end 0.7874 0.4064)
			(stroke
				(width 0.1524)
				(type default)
			)
			(layer "B.SilkS")
		)
		(fp_line
			(start 0.67945 -0.305054)
			(end 0.12065 -0.305054)
			(stroke
				(width 0.1)
				(type default)
			)
			(layer "B.Fab")
		)
		(fp_line
			(start 0.12065 -0.305054)
			(end 0.12065 -0.2794)
			(stroke
				(width 0.1)
				(type default)
			)
			(layer "B.Fab")
		)
		(fp_line
			(start -0.12065 -0.3048)
			(end -0.67945 -0.3048)
			(stroke
				(width 0.1)
				(type default)
			)
			(layer "B.Fab")
		)
		(fp_line
			(start -0.67945 -0.3048)
			(end -0.67945 0.3048)
			(stroke
				(width 0.1)
				(type default)
			)
			(layer "B.Fab")
		)
		(fp_line
			(start 0.12065 -0.2794)
			(end -0.12065 -0.2794)
			(stroke
				(width 0.1)
				(type default)
			)
			(layer "B.Fab")
		)
		(fp_line
			(start -0.12065 -0.2794)
			(end -0.12065 -0.3048)
			(stroke
				(width 0.1)
				(type default)
			)
			(layer "B.Fab")
		)
		(fp_line
			(start 0.12065 0.2794)
			(end 0.12065 0.3048)
			(stroke
				(width 0.1)
				(type default)
			)
			(layer "B.Fab")
		)
		(fp_line
			(start -0.120396 0.2794)
			(end 0.12065 0.2794)
			(stroke
				(width 0.1)
				(type default)
			)
			(layer "B.Fab")
		)
		(fp_line
			(start 0.67945 0.3048)
			(end 0.67945 -0.305054)
			(stroke
				(width 0.1)
				(type default)
			)
			(layer "B.Fab")
		)
		(fp_line
			(start 0.12065 0.3048)
			(end 0.67945 0.3048)
			(stroke
				(width 0.1)
				(type default)
			)
			(layer "B.Fab")
		)
		(fp_line
			(start -0.120396 0.3048)
			(end -0.120396 0.2794)
			(stroke
				(width 0.1)
				(type default)
			)
			(layer "B.Fab")
		)
		(fp_line
			(start -0.67945 0.3048)
			(end -0.120396 0.3048)
			(stroke
				(width 0.1)
				(type default)
			)
			(layer "B.Fab")
		)
		(pad "1" smd circle
			(at 0.40005 0 270)
			(size 0 0)
			(layers "B.Cu" "B.Mask" "B.Paste")
			(net "P3V3_AUX")
		)
		(pad "2" smd circle
			(at -0.40005 0 270)
			(size 0 0)
			(layers "B.Cu" "B.Mask" "B.Paste")
			(net "TP_P0V9_RETIMER_CPU1_VRHOT")
		)
	)
)
